# T6G (Grand Teton) — schematic netlist excerpt (pin names and nets, part order shuffled) for the footprints in the layout excerpt that follows; sources: Cadence DE-HDL packaged netlist, KiCad conversion of 04192023_DAF0TMB3IC0_F0TG_MB_C_brd_V02_OCP.brd

R419  Q_RES  0 5% CHIP  pkg 0402LF  page 80 : A = RST_SRST_PLD_BMC_N ; B = RST_SRST_PLD_BMC_R_N
PC366  Q_CAP  10UF 6.3V 20% X6S  pkg C0402  page 217 : A = PVDDCR_CPU1_P1_VCCS ; B = GND

(kicad_pcb
	(version 20260206)
	(generator "pcbnew")
	(generator_version "10.0")
	(general
		(thickness 1.6)
		(legacy_teardrops no)
	)
	(paper "A4")
	(title_block
		(title "04192023_DAF0TMB3IC0_F0TG_MB_C_brd_V02_OCP.brd")
		(comment 1 "Grand Teton / footprints 2072-2073 of 8354")
	)
	(layers
		(0 "F.Cu" signal "TOP")
		(4 "In1.Cu" signal "GND")
		(6 "In2.Cu" signal "IN1")
		(8 "In3.Cu" signal "GND1")
		(10 "In4.Cu" signal "IN2")
		(12 "In5.Cu" signal "GND2")
		(14 "In6.Cu" signal "IN3")
		(16 "In7.Cu" signal "GND3")
		(18 "In8.Cu" signal "VCC")
		(20 "In9.Cu" signal "VCC1")
		(22 "In10.Cu" signal "GND4")
		(24 "In11.Cu" signal "IN4")
		(26 "In12.Cu" signal "GND5")
		(28 "In13.Cu" signal "IN5")
		(30 "In14.Cu" signal "GND6")
		(32 "In15.Cu" signal "IN6")
		(34 "In16.Cu" signal "GND7")
		(2 "B.Cu" signal "BOTTOM")
		(9 "F.Adhes" user "F.Adhesive")
		(11 "B.Adhes" user "B.Adhesive")
		(13 "F.Paste" user "Package Geometry/Pastemask Top")
		(15 "B.Paste" user "Package Geometry/Pastemask Bottom")
		(5 "F.SilkS" user "Ref Des/Silkscreen Top")
		(7 "B.SilkS" user "Ref Des/Silkscreen Bottom")
		(1 "F.Mask" user "Board Geometry/Soldermask Top")
		(3 "B.Mask" user "Board Geometry/Soldermask Bottom")
		(17 "Dwgs.User" user "User.Drawings")
		(19 "Cmts.User" user "User.Comments")
		(21 "Eco1.User" user "User.Eco1")
		(23 "Eco2.User" user "User.Eco2")
		(25 "Edge.Cuts" user "Board Geometry/Outline")
		(27 "Margin" user)
		(31 "F.CrtYd" user "Package Geometry/Place Bound Top")
		(29 "B.CrtYd" user "Package Geometry/Place Bound Bottom")
		(35 "F.Fab" user "Ref Des/Assembly Top")
		(33 "B.Fab" user "Ref Des/Assembly Bottom")
	)
	(footprint ""
		(layer "F.Cu")
		(at 34.82848 -368.467132 90)
		(property "Reference" "PC366"
			(at 0 0 90)
			(layer "F.SilkS")
			(hide yes)
			(effects
				(font
					(size 1.27 1.27)
				)
			)
		)
		(property "Value" ""
			(at 0 0 90)
			(layer "F.Fab")
			(effects
				(font
					(size 1.27 1.27)
				)
			)
		)
		(duplicate_pad_numbers_are_jumpers no)
		(fp_line
			(start 0.7874 -0.4064)
			(end 0.7874 0.4064)
			(stroke
				(width 0.1524)
				(type default)
			)
			(layer "F.SilkS")
		)
		(fp_line
			(start -0.7874 -0.4064)
			(end 0.7874 -0.4064)
			(stroke
				(width 0.1524)
				(type default)
			)
			(layer "F.SilkS")
		)
		(fp_line
			(start 0.7874 0.4064)
			(end -0.7874 0.4064)
			(stroke
				(width 0.1524)
				(type default)
			)
			(layer "F.SilkS")
		)
		(fp_line
			(start -0.7874 0.4064)
			(end -0.7874 -0.4064)
			(stroke
				(width 0.1524)
				(type default)
			)
			(layer "F.SilkS")
		)
		(fp_line
			(start -0.12065 -0.305054)
			(end -0.12065 -0.2794)
			(stroke
				(width 0.1)
				(type default)
			)
			(layer "F.Fab")
		)
		(fp_line
			(start -0.67945 -0.305054)
			(end -0.12065 -0.305054)
			(stroke
				(width 0.1)
				(type default)
			)
			(layer "F.Fab")
		)
		(fp_line
			(start 0.67945 -0.3048)
			(end 0.67945 0.3048)
			(stroke
				(width 0.1)
				(type default)
			)
			(layer "F.Fab")
		)
		(fp_line
			(start 0.12065 -0.3048)
			(end 0.67945 -0.3048)
			(stroke
				(width 0.1)
				(type default)
			)
			(layer "F.Fab")
		)
		(fp_line
			(start 0.12065 -0.2794)
			(end 0.12065 -0.3048)
			(stroke
				(width 0.1)
				(type default)
			)
			(layer "F.Fab")
		)
		(fp_line
			(start -0.12065 -0.2794)
			(end 0.12065 -0.2794)
			(stroke
				(width 0.1)
				(type default)
			)
			(layer "F.Fab")
		)
		(fp_line
			(start 0.120396 0.2794)
			(end -0.12065 0.2794)
			(stroke
				(width 0.1)
				(type default)
			)
			(layer "F.Fab")
		)
		(fp_line
			(start -0.12065 0.2794)
			(end -0.12065 0.3048)
			(stroke
				(width 0.1)
				(type default)
			)
			(layer "F.Fab")
		)
		(fp_line
			(start 0.67945 0.3048)
			(end 0.120396 0.3048)
			(stroke
				(width 0.1)
				(type default)
			)
			(layer "F.Fab")
		)
		(fp_line
			(start 0.120396 0.3048)
			(end 0.120396 0.2794)
			(stroke
				(width 0.1)
				(type default)
			)
			(layer "F.Fab")
		)
		(fp_line
			(start -0.12065 0.3048)
			(end -0.67945 0.3048)
			(stroke
				(width 0.1)
				(type default)
			)
			(layer "F.Fab")
		)
		(fp_line
			(start -0.67945 0.3048)
			(end -0.67945 -0.305054)
			(stroke
				(width 0.1)
				(type default)
			)
			(layer "F.Fab")
		)
		(pad "1" smd circle
			(at -0.40005 0 90)
			(size 0 0)
			(layers "F.Cu" "F.Mask" "F.Paste")
			(net "PVDDCR_CPU1_P1_VCCS")
		)
		(pad "2" smd circle
			(at 0.40005 0 90)
			(size 0 0)
			(layers "F.Cu" "F.Mask" "F.Paste")
			(net "GND")
		)
	)
	(footprint ""
		(layer "F.Cu")
		(at 165.62451 -123.683014)
		(property "Reference" "R419"
			(at 0 0 0)
			(layer "F.SilkS")
			(hide yes)
			(effects
				(font
					(size 1.27 1.27)
				)
			)
		)
		(property "Value" ""
			(at 0 0 0)
			(layer "F.Fab")
			(effects
				(font
					(size 1.27 1.27)
				)
			)
		)
		(duplicate_pad_numbers_are_jumpers no)
		(fp_line
			(start -0.7874 -0.4064)
			(end 0.7874 -0.4064)
			(stroke
				(width 0.1524)
				(type default)
			)
			(layer "F.SilkS")
		)
		(fp_line
			(start -0.7874 0.4064)
			(end -0.7874 -0.4064)
			(stroke
				(width 0.1524)
				(type default)
			)
			(layer "F.SilkS")
		)
		(fp_line
			(start 0.7874 -0.4064)
			(end 0.7874 0.4064)
			(stroke
				(width 0.1524)
				(type default)
			)
			(layer "F.SilkS")
		)
		(fp_line
			(start 0.7874 0.4064)
			(end -0.7874 0.4064)
			(stroke
				(width 0.1524)
				(type default)
			)
			(layer "F.SilkS")
		)
		(fp_line
			(start -0.67945 -0.305054)
			(end -0.12065 -0.305054)
			(stroke
				(width 0.1)
				(type default)
			)
			(layer "F.Fab")
		)
		(fp_line
			(start -0.67945 0.3048)
			(end -0.67945 -0.305054)
			(stroke
				(width 0.1)
				(type default)
			)
			(layer "F.Fab")
		)
		(fp_line
			(start -0.12065 -0.305054)
			(end -0.12065 -0.2794)
			(stroke
				(width 0.1)
				(type default)
			)
			(layer "F.Fab")
		)
		(fp_line
			(start -0.12065 -0.2794)
			(end 0.12065 -0.2794)
			(stroke
				(width 0.1)
				(type default)
			)
			(layer "F.Fab")
		)
		(fp_line
			(start -0.12065 0.2794)
			(end -0.12065 0.3048)
			(stroke
				(width 0.1)
				(type default)
			)
			(layer "F.Fab")
		)
		(fp_line
			(start -0.12065 0.3048)
			(end -0.67945 0.3048)
			(stroke
				(width 0.1)
				(type default)
			)
			(layer "F.Fab")
		)
		(fp_line
			(start 0.120396 0.2794)
			(end -0.12065 0.2794)
			(stroke
				(width 0.1)
				(type default)
			)
			(layer "F.Fab")
		)
		(fp_line
			(start 0.120396 0.3048)
			(end 0.120396 0.2794)
			(stroke
				(width 0.1)
				(type default)
			)
			(layer "F.Fab")
		)
		(fp_line
			(start 0.12065 -0.3048)
			(end 0.67945 -0.3048)
			(stroke
				(width 0.1)
				(type default)
			)
			(layer "F.Fab")
		)
		(fp_line
			(start 0.12065 -0.2794)
			(end 0.12065 -0.3048)
			(stroke
				(width 0.1)
				(type default)
			)
			(layer "F.Fab")
		)
		(fp_line
			(start 0.67945 -0.3048)
			(end 0.67945 0.3048)
			(stroke
				(width 0.1)
				(type default)
			)
			(layer "F.Fab")
		)
		(fp_line
			(start 0.67945 0.3048)
			(end 0.120396 0.3048)
			(stroke
				(width 0.1)
				(type default)
			)
			(layer "F.Fab")
		)
		(pad "1" smd circle
			(at -0.40005 0)
			(size 0 0)
			(layers "F.Cu" "F.Mask" "F.Paste")
			(net "RST_SRST_PLD_BMC_N")
		)
		(pad "2" smd circle
			(at 0.40005 0)
			(size 0 0)
			(layers "F.Cu" "F.Mask" "F.Paste")
			(net "RST_SRST_PLD_BMC_R_N")
		)
	)
)
